(kicad_pcb
	(version 20260206)
	(generator "pcbnew")
	(generator_version "10.0")
	(general
		(thickness 1.6)
		(legacy_teardrops no)
	)
	(paper "A4")
	(title_block
		(title "04192023_DAF0TMB3IC0_F0TG_MB_C_brd_V02_OCP.brd")
		(comment 1 "Grand Teton / footprints 3167-3168 of 8354")
	)
	(layers
		(0 "F.Cu" signal "TOP")
		(4 "In1.Cu" signal "GND")
		(6 "In2.Cu" signal "IN1")
		(8 "In3.Cu" signal "GND1")
		(10 "In4.Cu" signal "IN2")
		(12 "In5.Cu" signal "GND2")
		(14 "In6.Cu" signal "IN3")
		(16 "In7.Cu" signal "GND3")
		(18 "In8.Cu" signal "VCC")
		(20 "In9.Cu" signal "VCC1")
		(22 "In10.Cu" signal "GND4")
		(24 "In11.Cu" signal "IN4")
		(26 "In12.Cu" signal "GND5")
		(28 "In13.Cu" signal "IN5")
		(30 "In14.Cu" signal "GND6")
		(32 "In15.Cu" signal "IN6")
		(34 "In16.Cu" signal "GND7")
		(2 "B.Cu" signal "BOTTOM")
		(9 "F.Adhes" user "F.Adhesive")
		(11 "B.Adhes" user "B.Adhesive")
		(13 "F.Paste" user "Package Geometry/Pastemask Top")
		(15 "B.Paste" user "Package Geometry/Pastemask Bottom")
		(5 "F.SilkS" user "Ref Des/Silkscreen Top")
		(7 "B.SilkS" user "Ref Des/Silkscreen Bottom")
		(1 "F.Mask" user "Board Geometry/Soldermask Top")
		(3 "B.Mask" user "Board Geometry/Soldermask Bottom")
		(17 "Dwgs.User" user "User.Drawings")
		(19 "Cmts.User" user "User.Comments")
		(21 "Eco1.User" user "User.Eco1")
		(23 "Eco2.User" user "User.Eco2")
		(25 "Edge.Cuts" user "Board Geometry/Outline")
		(27 "Margin" user)
		(31 "F.CrtYd" user "Package Geometry/Place Bound Top")
		(29 "B.CrtYd" user "Package Geometry/Place Bound Bottom")
		(35 "F.Fab" user "Ref Des/Assembly Top")
		(33 "B.Fab" user "Ref Des/Assembly Bottom")
	)
	(footprint ""
		(layer "F.Cu")
		(at 64.708024 -40.208708 90)
		(property "Reference" "R4067"
			(at 0 0 90)
			(layer "F.SilkS")
			(hide yes)
			(effects
				(font
					(size 1.27 1.27)
				)
			)
		)
		(property "Value" ""
			(at 0 0 90)
			(layer "F.Fab")
			(effects
				(font
					(size 1.27 1.27)
				)
			)
		)
		(duplicate_pad_numbers_are_jumpers no)
		(fp_line
			(start 0.7874 -0.4064)
			(end 0.7874 0.4064)
			(stroke
				(width 0.1524)
				(type default)
			)
			(layer "F.SilkS")
		)
		(fp_line
			(start -0.7874 -0.4064)
			(end 0.7874 -0.4064)
			(stroke
				(width 0.1524)
				(type default)
			)
			(layer "F.SilkS")
		)
		(fp_line
			(start 0.7874 0.4064)
			(end -0.7874 0.4064)
			(stroke
				(width 0.1524)
				(type default)
			)
			(layer "F.SilkS")
		)
		(fp_line
			(start -0.7874 0.4064)
			(end -0.7874 -0.4064)
			(stroke
				(width 0.1524)
				(type default)
			)
			(layer "F.SilkS")
		)
		(fp_line
			(start -0.12065 -0.305054)
			(end -0.12065 -0.2794)
			(stroke
				(width 0.1)
				(type default)
			)
			(layer "F.Fab")
		)
		(fp_line
			(start -0.67945 -0.305054)
			(end -0.12065 -0.305054)
			(stroke
				(width 0.1)
				(type default)
			)
			(layer "F.Fab")
		)
		(fp_line
			(start 0.67945 -0.3048)
			(end 0.67945 0.3048)
			(stroke
				(width 0.1)
				(type default)
			)
			(layer "F.Fab")
		)
		(fp_line
			(start 0.12065 -0.3048)
			(end 0.67945 -0.3048)
			(stroke
				(width 0.1)
				(type default)
			)
			(layer "F.Fab")
		)
		(fp_line
			(start 0.12065 -0.2794)
			(end 0.12065 -0.3048)
			(stroke
				(width 0.1)
				(type default)
			)
			(layer "F.Fab")
		)
		(fp_line
			(start -0.12065 -0.2794)
			(end 0.12065 -0.2794)
			(stroke
				(width 0.1)
				(type default)
			)
			(layer "F.Fab")
		)
		(fp_line
			(start 0.120396 0.2794)
			(end -0.12065 0.2794)
			(stroke
				(width 0.1)
				(type default)
			)
			(layer "F.Fab")
		)
		(fp_line
			(start -0.12065 0.2794)
			(end -0.12065 0.3048)
			(stroke
				(width 0.1)
				(type default)
			)
			(layer "F.Fab")
		)
		(fp_line
			(start 0.67945 0.3048)
			(end 0.120396 0.3048)
			(stroke
				(width 0.1)
				(type default)
			)
			(layer "F.Fab")
		)
		(fp_line
			(start 0.120396 0.3048)
			(end 0.120396 0.2794)
			(stroke
				(width 0.1)
				(type default)
			)
			(layer "F.Fab")
		)
		(fp_line
			(start -0.12065 0.3048)
			(end -0.67945 0.3048)
			(stroke
				(width 0.1)
				(type default)
			)
			(layer "F.Fab")
		)
		(fp_line
			(start -0.67945 0.3048)
			(end -0.67945 -0.305054)
			(stroke
				(width 0.1)
				(type default)
			)
			(layer "F.Fab")
		)
		(pad "1" smd circle
			(at -0.40005 0 90)
			(size 0 0)
			(layers "F.Cu" "F.Mask" "F.Paste")
			(net "P12V_AUX")
		)
		(pad "2" smd circle
			(at 0.40005 0 90)
			(size 0 0)
			(layers "F.Cu" "F.Mask" "F.Paste")
			(net "P3V3_OCP_2_EN_G")
		)
	)
	(footprint ""
		(layer "F.Cu")
		(at 28.534106 19.444716 -90)
		(property "Reference" "LBL_1"
			(at 0 0 270)
			(layer "F.SilkS")
			(hide yes)
			(effects
				(font
					(size 1.27 1.27)
				)
			)
		)
		(property "Value" ""
			(at 0 0 270)
			(layer "F.Fab")
			(effects
				(font
					(size 1.27 1.27)
				)
			)
		)
		(duplicate_pad_numbers_are_jumpers no)
		(pad "1" smd circle
			(at 0 0 270)
			(size 0.762 0.762)
			(layers "F.Cu" "F.Mask" "F.Paste")
			(net "Net_10817")
		)
	)
)
